(kicad_pcb
	(version 20241229)
	(generator "pcbnew")
	(generator_version "9.0")
	(general
		(thickness 1.294)
		(legacy_teardrops no)
	)
	(paper "A3")
	(title_block
		(title "Kintex 410T devboard")
		(date "2024-04-03")
		(rev "1.1.2")
		(comment 9 "footprints 325-329 of 975")
	)
	(layers
		(0 "F.Cu" mixed)
		(4 "In1.Cu" power)
		(6 "In2.Cu" power)
		(8 "In3.Cu" mixed)
		(10 "In4.Cu" power)
		(12 "In5.Cu" mixed)
		(14 "In6.Cu" power)
		(16 "In7.Cu" mixed)
		(18 "In8.Cu" power)
		(2 "B.Cu" mixed)
		(9 "F.Adhes" user "F.Adhesive")
		(11 "B.Adhes" user "B.Adhesive")
		(13 "F.Paste" user)
		(15 "B.Paste" user)
		(5 "F.SilkS" user "F.Silkscreen")
		(7 "B.SilkS" user "B.Silkscreen")
		(1 "F.Mask" user)
		(3 "B.Mask" user)
		(17 "Dwgs.User" user "User.Drawings")
		(19 "Cmts.User" user "User.Comments")
		(21 "Eco1.User" user "User.Eco1")
		(23 "Eco2.User" user "User.Eco2")
		(25 "Edge.Cuts" user)
		(27 "Margin" user)
		(31 "F.CrtYd" user "F.Courtyard")
		(29 "B.CrtYd" user "B.Courtyard")
		(35 "F.Fab" user)
		(33 "B.Fab" user)
	)
	(footprint "antmicro-footprints:C_0402_1005Metric"
		(layer "F.Cu")
		(at 201.6625 88.3365 -90)
		(descr "Capacitor SMD 0402")
		(tags "capacitor SMD 0402")
		(property "Reference" "C281"
			(at -0.8865 -0.3875 270)
			(layer "F.SilkS")
			(effects
				(font
					(size 0.7 0.7)
					(thickness 0.15)
				)
				(justify left bottom)
			)
		)
		(property "Value" "C_100n_0402"
			(at 0 1.169 270)
			(layer "F.Fab")
			(effects
				(font
					(size 0.7 0.7)
					(thickness 0.15)
				)
				(justify left bottom)
			)
		)
		(property "Description" "SMD Multilayer Ceramic Capacitor, 0.1 µF, 50 V, 0402 [1005 Metric], ± 10%, X5R, GRM Series"
			(at 0 0 270)
			(layer "F.Fab")
			(hide yes)
			(effects
				(font
					(size 1.27 1.27)
					(thickness 0.15)
				)
			)
		)
		(property "Author" "Antmicro"
			(at 113.326 289.999 0)
			(layer "F.Fab")
			(hide yes)
			(effects
				(font
					(size 1 1)
					(thickness 0.15)
				)
			)
		)
		(property "Dielectric" "X5R"
			(at 113.326 289.999 0)
			(layer "F.Fab")
			(hide yes)
			(effects
				(font
					(size 1 1)
					(thickness 0.15)
				)
			)
		)
		(property "License" "Apache-2.0"
			(at 113.326 289.999 0)
			(layer "F.Fab")
			(hide yes)
			(effects
				(font
					(size 1 1)
					(thickness 0.15)
				)
			)
		)
		(property "MPN" "GRM155R61H104KE14D"
			(at 113.326 289.999 0)
			(layer "F.Fab")
			(hide yes)
			(effects
				(font
					(size 1 1)
					(thickness 0.15)
				)
			)
		)
		(property "Manufacturer" "Murata"
			(at 113.326 289.999 0)
			(layer "F.Fab")
			(hide yes)
			(effects
				(font
					(size 1 1)
					(thickness 0.15)
				)
			)
		)
		(property "Val" "100n"
			(at 113.326 289.999 0)
			(layer "F.Fab")
			(hide yes)
			(effects
				(font
					(size 1 1)
					(thickness 0.15)
				)
			)
		)
		(property "Voltage" "50V"
			(at 113.326 289.999 0)
			(layer "F.Fab")
			(hide yes)
			(effects
				(font
					(size 1 1)
					(thickness 0.15)
				)
			)
		)
		(sheetname "HDMI + Ethernet")
		(sheetfile "hdmi-ethernet.kicad_sch")
		(attr smd)
		(fp_rect
			(start -0.925 -0.47)
			(end 0.925 0.47)
			(stroke
				(width 0.05)
				(type default)
			)
			(fill no)
			(layer "F.CrtYd")
		)
		(fp_line
			(start -0.494 0.248)
			(end -0.494 -0.25)
			(stroke
				(width 0.15)
				(type solid)
			)
			(layer "F.Fab")
		)
		(fp_line
			(start 0.504 0.248)
			(end -0.494 0.248)
			(stroke
				(width 0.15)
				(type solid)
			)
			(layer "F.Fab")
		)
		(fp_line
			(start -0.494 -0.25)
			(end 0.504 -0.25)
			(stroke
				(width 0.15)
				(type solid)
			)
			(layer "F.Fab")
		)
		(fp_line
			(start 0.504 -0.25)
			(end 0.504 0.248)
			(stroke
				(width 0.15)
				(type solid)
			)
			(layer "F.Fab")
		)
		(pad "1" smd roundrect
			(at -0.48 0 270)
			(size 0.59 0.64)
			(layers "F.Cu" "F.Mask" "F.Paste")
			(roundrect_rratio 0.25)
			(net 1 "GND")
			(pintype "passive")
		)
		(pad "2" smd roundrect
			(at 0.48 0 270)
			(size 0.59 0.64)
			(layers "F.Cu" "F.Mask" "F.Paste")
			(roundrect_rratio 0.25)
			(net 727 "+1V2")
			(pintype "passive")
		)
	)
	(footprint "antmicro-footprints:SC70-3"
		(layer "F.Cu")
		(at 258.4 91)
		(property "Reference" "Q11"
			(at -1.6 1.1 90)
			(layer "F.SilkS")
			(effects
				(font
					(size 0.7 0.7)
					(thickness 0.15)
				)
				(justify left bottom)
			)
		)
		(property "Value" "BSS138PW"
			(at 0 2.3 0)
			(layer "F.Fab")
			(effects
				(font
					(size 0.7 0.7)
					(thickness 0.15)
				)
				(justify left bottom)
			)
		)
		(property "Description" "Power MOSFET, N Channel, 60 V, 320 mA, 0.9 ohm, SOT-323, Surface Mount"
			(at 0 0 0)
			(layer "F.Fab")
			(hide yes)
			(effects
				(font
					(size 1.27 1.27)
					(thickness 0.15)
				)
			)
		)
		(property "Author" "Antmicro"
			(at 0 0 0)
			(layer "F.Fab")
			(hide yes)
			(effects
				(font
					(size 1 1)
					(thickness 0.15)
				)
			)
		)
		(property "License" "Apache-2.0"
			(at 0 0 0)
			(layer "F.Fab")
			(hide yes)
			(effects
				(font
					(size 1 1)
					(thickness 0.15)
				)
			)
		)
		(property "MPN" "BSS138PW"
			(at 0 0 0)
			(layer "F.Fab")
			(hide yes)
			(effects
				(font
					(size 1 1)
					(thickness 0.15)
				)
			)
		)
		(property "Manufacturer" "Nexperia"
			(at 0 0 0)
			(layer "F.Fab")
			(hide yes)
			(effects
				(font
					(size 1 1)
					(thickness 0.15)
				)
			)
		)
		(sheetname "User GPIO + LED + button + DIP switch")
		(sheetfile "user-gpio.kicad_sch")
		(attr smd)
		(fp_line
			(start -0.3 -1)
			(end 0.627 -0.999)
			(stroke
				(width 0.15)
				(type solid)
			)
			(layer "F.SilkS")
		)
		(fp_line
			(start -0.3 1)
			(end 0.627 1.001)
			(stroke
				(width 0.15)
				(type solid)
			)
			(layer "F.SilkS")
		)
		(fp_line
			(start 0.627 -0.6)
			(end 0.627 -0.999)
			(stroke
				(width 0.15)
				(type solid)
			)
			(layer "F.SilkS")
		)
		(fp_line
			(start 0.627 0.6)
			(end 0.627 1.001)
			(stroke
				(width 0.15)
				(type solid)
			)
			(layer "F.SilkS")
		)
		(fp_line
			(start -1.4 1)
			(end -1.4 -1)
			(stroke
				(width 0.05)
				(type solid)
			)
			(layer "F.CrtYd")
		)
		(fp_line
			(start -0.9 -1.3)
			(end -0.9 -1)
			(stroke
				(width 0.05)
				(type solid)
			)
			(layer "F.CrtYd")
		)
		(fp_line
			(start -0.9 -1.3)
			(end 0.9 -1.3)
			(stroke
				(width 0.05)
				(type solid)
			)
			(layer "F.CrtYd")
		)
		(fp_line
			(start -0.9 -1)
			(end -1.4 -1)
			(stroke
				(width 0.05)
				(type solid)
			)
			(layer "F.CrtYd")
		)
		(fp_line
			(start -0.9 1)
			(end -1.4 1)
			(stroke
				(width 0.05)
				(type solid)
			)
			(layer "F.CrtYd")
		)
		(fp_line
			(start -0.9 1.3)
			(end -0.9 1)
			(stroke
				(width 0.05)
				(type solid)
			)
			(layer "F.CrtYd")
		)
		(fp_line
			(start 0.9 -1.3)
			(end 0.9 -0.4)
			(stroke
				(width 0.05)
				(type solid)
			)
			(layer "F.CrtYd")
		)
		(fp_line
			(start 0.9 -0.4)
			(end 1.4 -0.4)
			(stroke
				(width 0.05)
				(type solid)
			)
			(layer "F.CrtYd")
		)
		(fp_line
			(start 0.9 0.4)
			(end 0.9 1.3)
			(stroke
				(width 0.05)
				(type solid)
			)
			(layer "F.CrtYd")
		)
		(fp_line
			(start 0.9 1.3)
			(end -0.9 1.3)
			(stroke
				(width 0.05)
				(type solid)
			)
			(layer "F.CrtYd")
		)
		(fp_line
			(start 1.4 -0.4)
			(end 1.4 0.4)
			(stroke
				(width 0.05)
				(type solid)
			)
			(layer "F.CrtYd")
		)
		(fp_line
			(start 1.4 0.4)
			(end 0.9 0.4)
			(stroke
				(width 0.05)
				(type solid)
			)
			(layer "F.CrtYd")
		)
		(fp_rect
			(start -0.623 -0.999)
			(end 0.627 1.001)
			(stroke
				(width 0.15)
				(type solid)
			)
			(fill no)
			(layer "F.Fab")
		)
		(pad "1" smd rect
			(at -1.051 -0.65 90)
			(size 0.6 0.6)
			(layers "F.Cu" "F.Mask" "F.Paste")
			(net 1302 "/USER_IO.LED_GREEN3")
			(pinfunction "G")
			(pintype "passive")
		)
		(pad "2" smd rect
			(at -1.051 0.65 90)
			(size 0.6 0.6)
			(layers "F.Cu" "F.Mask" "F.Paste")
			(net 1 "GND")
			(pinfunction "S")
			(pintype "passive")
		)
		(pad "3" smd rect
			(at 1.05 0 90)
			(size 0.6 0.6)
			(layers "F.Cu" "F.Mask" "F.Paste")
			(net 23 "Net-(D21-C)")
			(pinfunction "D")
			(pintype "passive")
		)
	)
	(footprint "antmicro-footprints:QFN-2L_1.6x1x0.55mm"
		(layer "F.Cu")
		(at 232 159.8 180)
		(property "Reference" "D8"
			(at 1.05 -0.35 0)
			(layer "F.SilkS")
			(effects
				(font
					(size 0.7 0.7)
					(thickness 0.15)
				)
				(justify right bottom)
			)
		)
		(property "Value" "ESDA25P35-1U1M"
			(at 0 1.7 0)
			(layer "F.Fab")
			(effects
				(font
					(size 0.7 0.7)
					(thickness 0.15)
				)
				(justify right bottom)
			)
		)
		(property "Description" "Unidirectional TVS, 30 kV, QFN-2L, 22 V, 195 pF"
			(at 0 0 180)
			(layer "F.Fab")
			(hide yes)
			(effects
				(font
					(size 1.27 1.27)
					(thickness 0.15)
				)
			)
		)
		(property "Author" "Antmicro"
			(at 464 319.6 0)
			(layer "F.Fab")
			(hide yes)
			(effects
				(font
					(size 1 1)
					(thickness 0.15)
				)
			)
		)
		(property "License" "Apache-2.0"
			(at 464 319.6 0)
			(layer "F.Fab")
			(hide yes)
			(effects
				(font
					(size 1 1)
					(thickness 0.15)
				)
			)
		)
		(property "MPN" "ESDA25P35-1U1M"
			(at 464 319.6 0)
			(layer "F.Fab")
			(hide yes)
			(effects
				(font
					(size 1 1)
					(thickness 0.15)
				)
			)
		)
		(property "Manufacturer" "STMicroelectronics"
			(at 464 319.6 0)
			(layer "F.Fab")
			(hide yes)
			(effects
				(font
					(size 1 1)
					(thickness 0.15)
				)
			)
		)
		(property "Public" "False"
			(at 464 319.6 0)
			(layer "F.Fab")
			(hide yes)
			(effects
				(font
					(size 1 1)
					(thickness 0.15)
				)
			)
		)
		(sheetname "Power supply")
		(sheetfile "power-supply.kicad_sch")
		(attr smd)
		(fp_line
			(start 0.27 0.3)
			(end -0.27 0.3)
			(stroke
				(width 0.15)
				(type solid)
			)
			(layer "F.SilkS")
		)
		(fp_line
			(start 0.27 -0.3)
			(end -0.27 -0.3)
			(stroke
				(width 0.15)
				(type solid)
			)
			(layer "F.SilkS")
		)
		(fp_line
			(start -1.2 -0.4)
			(end -1.2 0.4)
			(stroke
				(width 0.15)
				(type solid)
			)
			(layer "F.SilkS")
		)
		(fp_rect
			(start 1.25 0.65)
			(end -1.25 -0.65)
			(stroke
				(width 0.05)
				(type solid)
			)
			(fill no)
			(layer "F.CrtYd")
		)
		(fp_line
			(start 0.599 0)
			(end 0.201 0)
			(stroke
				(width 0.15)
				(type solid)
			)
			(layer "F.Fab")
		)
		(fp_line
			(start 0.201 0.2)
			(end 0.201 0)
			(stroke
				(width 0.15)
				(type solid)
			)
			(layer "F.Fab")
		)
		(fp_line
			(start 0.201 0)
			(end 0.201 -0.202)
			(stroke
				(width 0.15)
				(type solid)
			)
			(layer "F.Fab")
		)
		(fp_line
			(start 0.201 -0.202)
			(end -0.101 0)
			(stroke
				(width 0.15)
				(type solid)
			)
			(layer "F.Fab")
		)
		(fp_line
			(start -0.101 0)
			(end 0.201 0.2)
			(stroke
				(width 0.15)
				(type solid)
			)
			(layer "F.Fab")
		)
		(fp_line
			(start -0.199 0.2)
			(end -0.199 0.1)
			(stroke
				(width 0.15)
				(type solid)
			)
			(layer "F.Fab")
		)
		(fp_line
			(start -0.199 0)
			(end -0.597 0)
			(stroke
				(width 0.15)
				(type solid)
			)
			(layer "F.Fab")
		)
		(fp_line
			(start -0.199 -0.202)
			(end -0.199 0.1)
			(stroke
				(width 0.15)
				(type solid)
			)
			(layer "F.Fab")
		)
		(fp_rect
			(start 0.848 0.4)
			(end -0.85 -0.402)
			(stroke
				(width 0.15)
				(type solid)
			)
			(fill no)
			(layer "F.Fab")
		)
		(pad "1" smd roundrect
			(at -0.7 0)
			(size 0.8 1)
			(layers "F.Cu" "F.Mask" "F.Paste")
			(roundrect_rratio 0.2)
			(net 704 "/Power supply/USB_DBG_PD.VBUS")
			(pinfunction "C")
			(pintype "passive")
		)
		(pad "2" smd roundrect
			(at 0.7 0)
			(size 0.8 1)
			(layers "F.Cu" "F.Mask" "F.Paste")
			(roundrect_rratio 0.2)
			(net 1 "GND")
			(pinfunction "A")
			(pintype "passive")
		)
	)
	(footprint "antmicro-footprints:C_0402_1005Metric"
		(layer "F.Cu")
		(at 164.7 139)
		(descr "Capacitor SMD 0402")
		(tags "capacitor SMD 0402")
		(property "Reference" "C188"
			(at -0.95 -1.45 0)
			(layer "F.SilkS")
			(effects
				(font
					(size 0.7 0.7)
					(thickness 0.15)
				)
				(justify left bottom)
			)
		)
		(property "Value" "C_10u_0402"
			(at 0 1.4 0)
			(layer "F.Fab")
			(effects
				(font
					(size 0.7 0.7)
					(thickness 0.15)
				)
				(justify left bottom)
			)
		)
		(property "Description" "SMD Multilayer Ceramic Capacitor, 10 µF, 6.3 V, 0402 [1005 Metric], ± 20%, X5R, CC Series"
			(at 0 0 0)
			(layer "F.Fab")
			(hide yes)
			(effects
				(font
					(size 1.27 1.27)
					(thickness 0.15)
				)
			)
		)
		(property "Author" "Antmicro"
			(at 0 0 0)
			(layer "F.Fab")
			(hide yes)
			(effects
				(font
					(size 1 1)
					(thickness 0.15)
				)
			)
		)
		(property "Dielectric" ""
			(at 0 0 0)
			(layer "F.Fab")
			(hide yes)
			(effects
				(font
					(size 1 1)
					(thickness 0.15)
				)
			)
		)
		(property "License" "Apache-2.0"
			(at 0 0 0)
			(layer "F.Fab")
			(hide yes)
			(effects
				(font
					(size 1 1)
					(thickness 0.15)
				)
			)
		)
		(property "MPN" "CC0402MRX5R5BB106"
			(at 0 0 0)
			(layer "F.Fab")
			(hide yes)
			(effects
				(font
					(size 1 1)
					(thickness 0.15)
				)
			)
		)
		(property "Manufacturer" "YAGEO"
			(at 0 0 0)
			(layer "F.Fab")
			(hide yes)
			(effects
				(font
					(size 1 1)
					(thickness 0.15)
				)
			)
		)
		(property "Val" "10u"
			(at 0 0 0)
			(layer "F.Fab")
			(hide yes)
			(effects
				(font
					(size 1 1)
					(thickness 0.15)
				)
			)
		)
		(property "Voltage" ""
			(at 0 0 0)
			(layer "F.Fab")
			(hide yes)
			(effects
				(font
					(size 1 1)
					(thickness 0.15)
				)
			)
		)
		(sheetname "DRAM + SRAM")
		(sheetfile "ram.kicad_sch")
		(attr smd)
		(fp_rect
			(start -0.925 -0.47)
			(end 0.925 0.47)
			(stroke
				(width 0.05)
				(type default)
			)
			(fill no)
			(layer "F.CrtYd")
		)
		(fp_line
			(start -0.494 -0.25)
			(end 0.504 -0.25)
			(stroke
				(width 0.15)
				(type solid)
			)
			(layer "F.Fab")
		)
		(fp_line
			(start -0.494 0.248)
			(end -0.494 -0.25)
			(stroke
				(width 0.15)
				(type solid)
			)
			(layer "F.Fab")
		)
		(fp_line
			(start 0.504 -0.25)
			(end 0.504 0.248)
			(stroke
				(width 0.15)
				(type solid)
			)
			(layer "F.Fab")
		)
		(fp_line
			(start 0.504 0.248)
			(end -0.494 0.248)
			(stroke
				(width 0.15)
				(type solid)
			)
			(layer "F.Fab")
		)
		(pad "1" smd roundrect
			(at -0.48 0)
			(size 0.59 0.64)
			(layers "F.Cu" "F.Mask" "F.Paste")
			(roundrect_rratio 0.25)
			(net 1 "GND")
			(pintype "passive")
		)
		(pad "2" smd roundrect
			(at 0.48 0)
			(size 0.59 0.64)
			(layers "F.Cu" "F.Mask" "F.Paste")
			(roundrect_rratio 0.25)
			(net 25 "+1V35")
			(pintype "passive")
		)
	)
	(footprint "antmicro-footprints:R_0402_1005Metric"
		(layer "F.Cu")
		(at 225.1 113.2)
		(descr "Resistor SMD 0402")
		(tags "resistor SMD 0402")
		(property "Reference" "R102"
			(at -3.65 0.4 0)
			(layer "F.SilkS")
			(effects
				(font
					(size 0.7 0.7)
					(thickness 0.15)
				)
				(justify left bottom)
			)
		)
		(property "Value" "R_0R_0402"
			(at 0 1.4 0)
			(layer "F.Fab")
			(effects
				(font
					(size 0.7 0.7)
					(thickness 0.15)
				)
				(justify left bottom)
			)
		)
		(property "Description" "SMD Chip Resistor, Jumper, 0 ohm, 100 mW, 0402 [1005 Metric], Thick Film, General Purpose"
			(at 0 0 0)
			(layer "F.Fab")
			(hide yes)
			(effects
				(font
					(size 1.27 1.27)
					(thickness 0.15)
				)
			)
		)
		(property "Author" "Antmicro"
			(at 0 0 0)
			(layer "F.Fab")
			(hide yes)
			(effects
				(font
					(size 1 1)
					(thickness 0.15)
				)
			)
		)
		(property "Current" "1A"
			(at 0 0 0)
			(layer "F.Fab")
			(hide yes)
			(effects
				(font
					(size 1 1)
					(thickness 0.15)
				)
			)
		)
		(property "License" "Apache-2.0"
			(at 0 0 0)
			(layer "F.Fab")
			(hide yes)
			(effects
				(font
					(size 1 1)
					(thickness 0.15)
				)
			)
		)
		(property "MPN" "ERJ2GE0R00X"
			(at 0 0 0)
			(layer "F.Fab")
			(hide yes)
			(effects
				(font
					(size 1 1)
					(thickness 0.15)
				)
			)
		)
		(property "Manufacturer" "Panasonic"
			(at 0 0 0)
			(layer "F.Fab")
			(hide yes)
			(effects
				(font
					(size 1 1)
					(thickness 0.15)
				)
			)
		)
		(property "Tolerance" ""
			(at 0 0 0)
			(layer "F.Fab")
			(hide yes)
			(effects
				(font
					(size 1 1)
					(thickness 0.15)
				)
			)
		)
		(property "Val" "0R"
			(at 0 0 0)
			(layer "F.Fab")
			(hide yes)
			(effects
				(font
					(size 1 1)
					(thickness 0.15)
				)
			)
		)
		(sheetname "SPI Flash + SD Card")
		(sheetfile "spi-flash.kicad_sch")
		(attr smd)
		(fp_rect
			(start -0.925 -0.47)
			(end 0.925 0.47)
			(stroke
				(width 0.05)
				(type default)
			)
			(fill no)
			(layer "F.CrtYd")
		)
		(fp_rect
			(start -0.5 -0.25)
			(end 0.5 0.25)
			(stroke
				(width 0.15)
				(type solid)
			)
			(fill no)
			(layer "F.Fab")
		)
		(pad "1" smd roundrect
			(at -0.48 0)
			(size 0.59 0.64)
			(layers "F.Cu" "F.Mask" "F.Paste")
			(roundrect_rratio 0.25)
			(net 430 "/FPGA Bank 16 & 17/USR_FLASH_1.DQ1")
			(pintype "passive")
		)
		(pad "2" smd roundrect
			(at 0.48 0)
			(size 0.59 0.64)
			(layers "F.Cu" "F.Mask" "F.Paste")
			(roundrect_rratio 0.25)
			(net 909 "/SPI Flash + SD Card/USR_FLASH_1_DQ1")
			(pintype "passive")
		)
	)
)
